(kicad_pcb
	(version 20260206)
	(generator "pcbnew")
	(generator_version "10.0")
	(general
		(thickness 1.6)
		(legacy_teardrops no)
	)
	(paper "A4")
	(title_block
		(title "Bryce Canyon_IOM_IOC_16318-2_OCP.brd")
		(comment 1 "Bryce Canyon / footprints 562-568 of 1605")
	)
	(layers
		(0 "F.Cu" signal "TOP")
		(4 "In1.Cu" signal "L2GND")
		(6 "In2.Cu" signal "L3")
		(8 "In3.Cu" signal "L4VCC")
		(10 "In4.Cu" signal "L5VCC")
		(12 "In5.Cu" signal "L6")
		(14 "In6.Cu" signal "L7GND")
		(2 "B.Cu" signal "BOTTOM")
		(9 "F.Adhes" user "F.Adhesive")
		(11 "B.Adhes" user "B.Adhesive")
		(13 "F.Paste" user "Package Geometry/Pastemask Top")
		(15 "B.Paste" user "Package Geometry/Pastemask Bottom")
		(5 "F.SilkS" user "Ref Des/Silkscreen Top")
		(7 "B.SilkS" user "Ref Des/Silkscreen Bottom")
		(1 "F.Mask" user "Board Geometry/Soldermask Top")
		(3 "B.Mask" user "Board Geometry/Soldermask Bottom")
		(17 "Dwgs.User" user "User.Drawings")
		(19 "Cmts.User" user "User.Comments")
		(21 "Eco1.User" user "User.Eco1")
		(23 "Eco2.User" user "User.Eco2")
		(25 "Edge.Cuts" user "Board Geometry/Outline")
		(27 "Margin" user)
		(31 "F.CrtYd" user "Package Geometry/Place Bound Top")
		(29 "B.CrtYd" user "Package Geometry/Place Bound Bottom")
		(35 "F.Fab" user "Ref Des/Assembly Top")
		(33 "B.Fab" user "Ref Des/Assembly Bottom")
	)
	(footprint ""
		(layer "F.Cu")
		(at 87.67445 -29.39034 180)
		(property "Reference" "C1"
			(at 0 0 180)
			(layer "F.SilkS")
			(hide yes)
			(effects
				(font
					(size 1.27 1.27)
				)
			)
		)
		(property "Value" "SCD1U16V2KX-3GP"
			(at 1.1811 -2.7051 180)
			(unlocked yes)
			(layer "F.Fab")
			(hide yes)
			(effects
				(font
					(size 1.016 1.016)
					(thickness 0.1524)
				)
			)
		)
		(property "Device Type" "C402H22"
			(at 1.1811 -4.2291 180)
			(unlocked yes)
			(layer "F.Fab")
			(hide yes)
			(effects
				(font
					(size 1.016 1.016)
					(thickness 0.1524)
				)
			)
		)
		(duplicate_pad_numbers_are_jumpers no)
		(fp_rect
			(start -0.4318 0.9525)
			(end 0.4318 -0.9525)
			(stroke
				(width 0)
				(type default)
			)
			(fill no)
			(layer "F.CrtYd")
		)
		(fp_rect
			(start -0.4318 0.9525)
			(end 0.4318 -0.9525)
			(stroke
				(width 0)
				(type default)
			)
			(fill no)
			(layer "F.Fab")
		)
		(pad "1" smd custom
			(at 0 -0.4445 180)
			(size 0.1524 0.1524)
			(layers "F.Cu" "F.Mask" "F.Paste")
			(net "P5V_STBY")
			(options
				(clearance outline)
				(anchor circle)
			)
			(primitives
				(gr_poly
					(pts
						(arc
							(start 0.3048 -0.2032)
							(mid 0.275042 -0.275042)
							(end 0.2032 -0.3048)
						)
						(arc
							(start -0.2032 -0.3048)
							(mid -0.275042 -0.275042)
							(end -0.3048 -0.2032)
						)
						(arc
							(start -0.3048 0.2032)
							(mid -0.275042 0.275042)
							(end -0.2032 0.3048)
						)
						(arc
							(start 0.2032 0.3048)
							(mid 0.275042 0.275042)
							(end 0.3048 0.2032)
						)
					)
					(width 0)
					(fill yes)
				)
			)
		)
		(pad "2" smd custom
			(at 0 0.4445 180)
			(size 0.1524 0.1524)
			(layers "F.Cu" "F.Mask" "F.Paste")
			(net "GND")
			(options
				(clearance outline)
				(anchor circle)
			)
			(primitives
				(gr_poly
					(pts
						(arc
							(start 0.3048 -0.2032)
							(mid 0.275042 -0.275042)
							(end 0.2032 -0.3048)
						)
						(arc
							(start -0.2032 -0.3048)
							(mid -0.275042 -0.275042)
							(end -0.3048 -0.2032)
						)
						(arc
							(start -0.3048 0.2032)
							(mid -0.275042 0.275042)
							(end -0.2032 0.3048)
						)
						(arc
							(start 0.2032 0.3048)
							(mid 0.275042 0.275042)
							(end 0.3048 0.2032)
						)
					)
					(width 0)
					(fill yes)
				)
			)
		)
	)
	(footprint ""
		(layer "F.Cu")
		(at 59.524392 -131.296156 180)
		(property "Reference" "R289"
			(at 0 0 180)
			(layer "F.SilkS")
			(hide yes)
			(effects
				(font
					(size 1.27 1.27)
				)
			)
		)
		(property "Value" "0R2J-2-GP"
			(at 0.064008 -3.993896 180)
			(unlocked yes)
			(layer "F.Fab")
			(hide yes)
			(effects
				(font
					(size 1.016 1.016)
					(thickness 0.1524)
				)
			)
		)
		(property "Device Type" "R402H16"
			(at 0.064008 -5.517896 180)
			(unlocked yes)
			(layer "F.Fab")
			(hide yes)
			(effects
				(font
					(size 1.016 1.016)
					(thickness 0.1524)
				)
			)
		)
		(duplicate_pad_numbers_are_jumpers no)
		(fp_line
			(start 0.508 -0.9398)
			(end -0.508 -0.9398)
			(stroke
				(width 0.1524)
				(type default)
			)
			(layer "F.SilkS")
		)
		(fp_line
			(start -0.508 -0.9398)
			(end -0.508 0.9398)
			(stroke
				(width 0.1524)
				(type default)
			)
			(layer "F.SilkS")
		)
		(fp_rect
			(start -0.508 0.9398)
			(end 0.508 -0.9398)
			(stroke
				(width 0)
				(type default)
			)
			(fill no)
			(layer "F.CrtYd")
		)
		(fp_rect
			(start -0.508 0.9398)
			(end 0.508 -0.9398)
			(stroke
				(width 0)
				(type default)
			)
			(fill no)
			(layer "F.Fab")
		)
		(pad "1" smd custom
			(at 0 -0.4445 180)
			(size 0.1397 0.1397)
			(layers "F.Cu" "F.Mask" "F.Paste")
			(net "EXP_SPARE_1")
			(options
				(clearance outline)
				(anchor circle)
			)
			(primitives
				(gr_poly
					(pts
						(arc
							(start -0.1778 -0.2794)
							(mid -0.249642 -0.249642)
							(end -0.2794 -0.1778)
						)
						(arc
							(start -0.2794 0.1778)
							(mid -0.249642 0.249642)
							(end -0.1778 0.2794)
						)
						(arc
							(start 0.1778 0.2794)
							(mid 0.249642 0.249642)
							(end 0.2794 0.1778)
						)
						(arc
							(start 0.2794 -0.1778)
							(mid 0.249642 -0.249642)
							(end 0.1778 -0.2794)
						)
					)
					(width 0)
					(fill yes)
				)
			)
		)
		(pad "2" smd custom
			(at 0 0.4445 180)
			(size 0.1397 0.1397)
			(layers "F.Cu" "F.Mask" "F.Paste")
			(net "EXP_SPARE_1_R")
			(options
				(clearance outline)
				(anchor circle)
			)
			(primitives
				(gr_poly
					(pts
						(arc
							(start -0.1778 -0.2794)
							(mid -0.249642 -0.249642)
							(end -0.2794 -0.1778)
						)
						(arc
							(start -0.2794 0.1778)
							(mid -0.249642 0.249642)
							(end -0.1778 0.2794)
						)
						(arc
							(start 0.1778 0.2794)
							(mid 0.249642 0.249642)
							(end 0.2794 0.1778)
						)
						(arc
							(start 0.2794 -0.1778)
							(mid 0.249642 -0.249642)
							(end 0.1778 -0.2794)
						)
					)
					(width 0)
					(fill yes)
				)
			)
		)
	)
	(footprint ""
		(layer "F.Cu")
		(at 8.904732 -138.145774 90)
		(property "Reference" "R229"
			(at 0 0 90)
			(layer "F.SilkS")
			(hide yes)
			(effects
				(font
					(size 1.27 1.27)
				)
			)
		)
		(property "Value" "120R2F-GP"
			(at 0.064008 -3.993896 90)
			(unlocked yes)
			(layer "F.Fab")
			(hide yes)
			(effects
				(font
					(size 1.016 1.016)
					(thickness 0.1524)
				)
			)
		)
		(property "Device Type" "R402H16"
			(at 0.064008 -5.517896 90)
			(unlocked yes)
			(layer "F.Fab")
			(hide yes)
			(effects
				(font
					(size 1.016 1.016)
					(thickness 0.1524)
				)
			)
		)
		(duplicate_pad_numbers_are_jumpers no)
		(fp_line
			(start 0.508 -0.9398)
			(end -0.508 -0.9398)
			(stroke
				(width 0.1524)
				(type default)
			)
			(layer "F.SilkS")
		)
		(fp_line
			(start -0.508 -0.9398)
			(end -0.508 0.9398)
			(stroke
				(width 0.1524)
				(type default)
			)
			(layer "F.SilkS")
		)
		(fp_rect
			(start -0.508 0.9398)
			(end 0.508 -0.9398)
			(stroke
				(width 0)
				(type default)
			)
			(fill no)
			(layer "F.CrtYd")
		)
		(fp_rect
			(start -0.508 0.9398)
			(end 0.508 -0.9398)
			(stroke
				(width 0)
				(type default)
			)
			(fill no)
			(layer "F.Fab")
		)
		(pad "1" smd custom
			(at 0 -0.4445 90)
			(size 0.1397 0.1397)
			(layers "F.Cu" "F.Mask" "F.Paste")
			(net "GND")
			(options
				(clearance outline)
				(anchor circle)
			)
			(primitives
				(gr_poly
					(pts
						(arc
							(start -0.1778 -0.2794)
							(mid -0.249642 -0.249642)
							(end -0.2794 -0.1778)
						)
						(arc
							(start -0.2794 0.1778)
							(mid -0.249642 0.249642)
							(end -0.1778 0.2794)
						)
						(arc
							(start 0.1778 0.2794)
							(mid 0.249642 0.249642)
							(end 0.2794 0.1778)
						)
						(arc
							(start 0.2794 -0.1778)
							(mid 0.249642 -0.249642)
							(end 0.1778 -0.2794)
						)
					)
					(width 0)
					(fill yes)
				)
			)
		)
		(pad "2" smd custom
			(at 0 0.4445 90)
			(size 0.1397 0.1397)
			(layers "F.Cu" "F.Mask" "F.Paste")
			(net "MEMBA_0")
			(options
				(clearance outline)
				(anchor circle)
			)
			(primitives
				(gr_poly
					(pts
						(arc
							(start -0.1778 -0.2794)
							(mid -0.249642 -0.249642)
							(end -0.2794 -0.1778)
						)
						(arc
							(start -0.2794 0.1778)
							(mid -0.249642 0.249642)
							(end -0.1778 0.2794)
						)
						(arc
							(start 0.1778 0.2794)
							(mid 0.249642 0.249642)
							(end 0.2794 0.1778)
						)
						(arc
							(start 0.2794 -0.1778)
							(mid 0.249642 -0.249642)
							(end 0.1778 -0.2794)
						)
					)
					(width 0)
					(fill yes)
				)
			)
		)
	)
	(footprint ""
		(layer "F.Cu")
		(at 197.0024 -49.9618)
		(property "Reference" "TP135"
			(at 0 0 0)
			(layer "F.SilkS")
			(hide yes)
			(effects
				(font
					(size 1.27 1.27)
				)
			)
		)
		(property "Value" "TPAD28-2-GP"
			(at -0.0127 -1.6637 0)
			(unlocked yes)
			(layer "F.Fab")
			(hide yes)
			(effects
				(font
					(size 1.016 1.016)
					(thickness 0.1524)
				)
			)
		)
		(property "Device Type" "TPAD28"
			(at -0.0127 -3.1877 0)
			(unlocked yes)
			(layer "F.Fab")
			(hide yes)
			(effects
				(font
					(size 1.016 1.016)
					(thickness 0.1524)
				)
			)
		)
		(duplicate_pad_numbers_are_jumpers no)
		(fp_poly
			(pts
				(arc
					(start 0.3556 0)
					(mid -0.3556 0)
					(end 0.3556 0)
				)
			)
			(stroke
				(width 0)
				(type default)
			)
			(fill no)
			(layer "F.CrtYd")
		)
		(fp_poly
			(pts
				(arc
					(start 0.6096 0)
					(mid -0.6096 0)
					(end 0.6096 0)
				)
			)
			(stroke
				(width 0)
				(type default)
			)
			(fill no)
			(layer "F.Fab")
		)
		(pad "1" smd circle
			(at 0 0)
			(size 0.7112 0.7112)
			(layers "F.Cu" "F.Mask" "F.Paste")
			(net "ICE0_TCK")
		)
	)
	(footprint ""
		(layer "F.Cu")
		(at 87.8586 -147.2692)
		(property "Reference" "R422"
			(at 0 0 0)
			(layer "F.SilkS")
			(hide yes)
			(effects
				(font
					(size 1.27 1.27)
				)
			)
		)
		(property "Value" "4K7R2F-GP"
			(at 0.064008 -3.993896 0)
			(unlocked yes)
			(layer "F.Fab")
			(hide yes)
			(effects
				(font
					(size 1.016 1.016)
					(thickness 0.1524)
				)
			)
		)
		(property "Device Type" "R402H16"
			(at 0.064008 -5.517896 0)
			(unlocked yes)
			(layer "F.Fab")
			(hide yes)
			(effects
				(font
					(size 1.016 1.016)
					(thickness 0.1524)
				)
			)
		)
		(duplicate_pad_numbers_are_jumpers no)
		(fp_line
			(start -0.508 -0.9398)
			(end -0.508 0.9398)
			(stroke
				(width 0.1524)
				(type default)
			)
			(layer "F.SilkS")
		)
		(fp_line
			(start 0.508 -0.9398)
			(end -0.508 -0.9398)
			(stroke
				(width 0.1524)
				(type default)
			)
			(layer "F.SilkS")
		)
		(fp_rect
			(start -0.508 0.9398)
			(end 0.508 -0.9398)
			(stroke
				(width 0)
				(type default)
			)
			(fill no)
			(layer "F.CrtYd")
		)
		(fp_rect
			(start -0.508 0.9398)
			(end 0.508 -0.9398)
			(stroke
				(width 0)
				(type default)
			)
			(fill no)
			(layer "F.Fab")
		)
		(pad "1" smd custom
			(at 0 -0.4445)
			(size 0.1397 0.1397)
			(layers "F.Cu" "F.Mask" "F.Paste")
			(net "P3V3_STBY")
			(options
				(clearance outline)
				(anchor circle)
			)
			(primitives
				(gr_poly
					(pts
						(arc
							(start -0.1778 -0.2794)
							(mid -0.249642 -0.249642)
							(end -0.2794 -0.1778)
						)
						(arc
							(start -0.2794 0.1778)
							(mid -0.249642 0.249642)
							(end -0.1778 0.2794)
						)
						(arc
							(start 0.1778 0.2794)
							(mid 0.249642 0.249642)
							(end 0.2794 0.1778)
						)
						(arc
							(start 0.2794 -0.1778)
							(mid 0.249642 -0.249642)
							(end 0.1778 -0.2794)
						)
					)
					(width 0)
					(fill yes)
				)
			)
		)
		(pad "2" smd custom
			(at 0 0.4445)
			(size 0.1397 0.1397)
			(layers "F.Cu" "F.Mask" "F.Paste")
			(net "IO_EXP0_RESET#_FLT")
			(options
				(clearance outline)
				(anchor circle)
			)
			(primitives
				(gr_poly
					(pts
						(arc
							(start -0.1778 -0.2794)
							(mid -0.249642 -0.249642)
							(end -0.2794 -0.1778)
						)
						(arc
							(start -0.2794 0.1778)
							(mid -0.249642 0.249642)
							(end -0.1778 0.2794)
						)
						(arc
							(start 0.1778 0.2794)
							(mid 0.249642 0.249642)
							(end 0.2794 0.1778)
						)
						(arc
							(start 0.2794 -0.1778)
							(mid 0.249642 -0.249642)
							(end 0.1778 -0.2794)
						)
					)
					(width 0)
					(fill yes)
				)
			)
		)
	)
	(footprint ""
		(layer "F.Cu")
		(at 37.9222 -164.2618 180)
		(property "Reference" "R330"
			(at 0 0 180)
			(layer "F.SilkS")
			(hide yes)
			(effects
				(font
					(size 1.27 1.27)
				)
			)
		)
		(property "Value" "4K7R2F-GP"
			(at 0.064008 -3.993896 180)
			(unlocked yes)
			(layer "F.Fab")
			(hide yes)
			(effects
				(font
					(size 1.016 1.016)
					(thickness 0.1524)
				)
			)
		)
		(property "Device Type" "R402H16"
			(at 0.064008 -5.517896 180)
			(unlocked yes)
			(layer "F.Fab")
			(hide yes)
			(effects
				(font
					(size 1.016 1.016)
					(thickness 0.1524)
				)
			)
		)
		(duplicate_pad_numbers_are_jumpers no)
		(fp_line
			(start 0.508 -0.9398)
			(end -0.508 -0.9398)
			(stroke
				(width 0.1524)
				(type default)
			)
			(layer "F.SilkS")
		)
		(fp_line
			(start -0.508 -0.9398)
			(end -0.508 0.9398)
			(stroke
				(width 0.1524)
				(type default)
			)
			(layer "F.SilkS")
		)
		(fp_rect
			(start -0.508 0.9398)
			(end 0.508 -0.9398)
			(stroke
				(width 0)
				(type default)
			)
			(fill no)
			(layer "F.CrtYd")
		)
		(fp_rect
			(start -0.508 0.9398)
			(end 0.508 -0.9398)
			(stroke
				(width 0)
				(type default)
			)
			(fill no)
			(layer "F.Fab")
		)
		(pad "1" smd custom
			(at 0 -0.4445 180)
			(size 0.1397 0.1397)
			(layers "F.Cu" "F.Mask" "F.Paste")
			(net "P3V3_STBY")
			(options
				(clearance outline)
				(anchor circle)
			)
			(primitives
				(gr_poly
					(pts
						(arc
							(start -0.1778 -0.2794)
							(mid -0.249642 -0.249642)
							(end -0.2794 -0.1778)
						)
						(arc
							(start -0.2794 0.1778)
							(mid -0.249642 0.249642)
							(end -0.1778 0.2794)
						)
						(arc
							(start 0.1778 0.2794)
							(mid 0.249642 0.249642)
							(end 0.2794 0.1778)
						)
						(arc
							(start 0.2794 -0.1778)
							(mid 0.249642 -0.249642)
							(end 0.1778 -0.2794)
						)
					)
					(width 0)
					(fill yes)
				)
			)
		)
		(pad "2" smd custom
			(at 0 0.4445 180)
			(size 0.1397 0.1397)
			(layers "F.Cu" "F.Mask" "F.Paste")
			(net "UART_EXP_BMC_TX")
			(options
				(clearance outline)
				(anchor circle)
			)
			(primitives
				(gr_poly
					(pts
						(arc
							(start -0.1778 -0.2794)
							(mid -0.249642 -0.249642)
							(end -0.2794 -0.1778)
						)
						(arc
							(start -0.2794 0.1778)
							(mid -0.249642 0.249642)
							(end -0.1778 0.2794)
						)
						(arc
							(start 0.1778 0.2794)
							(mid 0.249642 0.249642)
							(end 0.2794 0.1778)
						)
						(arc
							(start 0.2794 -0.1778)
							(mid 0.249642 -0.249642)
							(end 0.1778 -0.2794)
						)
					)
					(width 0)
					(fill yes)
				)
			)
		)
	)
	(footprint ""
		(layer "F.Cu")
		(at 81.858358 -139.812522 180)
		(property "Reference" "C30"
			(at 0 0 180)
			(layer "F.SilkS")
			(hide yes)
			(effects
				(font
					(size 1.27 1.27)
				)
			)
		)
		(property "Value" "SCD1U16V2KX-3GP"
			(at 1.1811 -2.7051 180)
			(unlocked yes)
			(layer "F.Fab")
			(hide yes)
			(effects
				(font
					(size 1.016 1.016)
					(thickness 0.1524)
				)
			)
		)
		(property "Device Type" "C402H22"
			(at 1.1811 -4.2291 180)
			(unlocked yes)
			(layer "F.Fab")
			(hide yes)
			(effects
				(font
					(size 1.016 1.016)
					(thickness 0.1524)
				)
			)
		)
		(duplicate_pad_numbers_are_jumpers no)
		(fp_rect
			(start -0.4318 0.9525)
			(end 0.4318 -0.9525)
			(stroke
				(width 0)
				(type default)
			)
			(fill no)
			(layer "F.CrtYd")
		)
		(fp_rect
			(start -0.4318 0.9525)
			(end 0.4318 -0.9525)
			(stroke
				(width 0)
				(type default)
			)
			(fill no)
			(layer "F.Fab")
		)
		(pad "1" smd custom
			(at 0 -0.4445 180)
			(size 0.1524 0.1524)
			(layers "F.Cu" "F.Mask" "F.Paste")
			(net "P3V3_STBY")
			(options
				(clearance outline)
				(anchor circle)
			)
			(primitives
				(gr_poly
					(pts
						(arc
							(start 0.3048 -0.2032)
							(mid 0.275042 -0.275042)
							(end 0.2032 -0.3048)
						)
						(arc
							(start -0.2032 -0.3048)
							(mid -0.275042 -0.275042)
							(end -0.3048 -0.2032)
						)
						(arc
							(start -0.3048 0.2032)
							(mid -0.275042 0.275042)
							(end -0.2032 0.3048)
						)
						(arc
							(start 0.2032 0.3048)
							(mid 0.275042 0.275042)
							(end 0.3048 0.2032)
						)
					)
					(width 0)
					(fill yes)
				)
			)
		)
		(pad "2" smd custom
			(at 0 0.4445 180)
			(size 0.1524 0.1524)
			(layers "F.Cu" "F.Mask" "F.Paste")
			(net "GND")
			(options
				(clearance outline)
				(anchor circle)
			)
			(primitives
				(gr_poly
					(pts
						(arc
							(start 0.3048 -0.2032)
							(mid 0.275042 -0.275042)
							(end 0.2032 -0.3048)
						)
						(arc
							(start -0.2032 -0.3048)
							(mid -0.275042 -0.275042)
							(end -0.3048 -0.2032)
						)
						(arc
							(start -0.3048 0.2032)
							(mid -0.275042 0.275042)
							(end -0.2032 0.3048)
						)
						(arc
							(start 0.2032 0.3048)
							(mid 0.275042 0.275042)
							(end 0.3048 0.2032)
						)
					)
					(width 0)
					(fill yes)
				)
			)
		)
	)
)
